(kicad_pcb
	(version 20241229)
	(generator "pcbnew")
	(generator_version "9.0")
	(general
		(thickness 1.711)
		(legacy_teardrops no)
	)
	(paper "A4")
	(title_block
		(title "Antmicro Baseboard for Jetson AGX Thor")
		(date "2026-02-18")
		(rev "1.1.0")
		(company "Antmicro Ltd")
		(comment 1 "www.antmicro.com")
		(comment 9 "footprints 440-443 of 1170")
	)
	(layers
		(0 "F.Cu" signal)
		(4 "In1.Cu" signal)
		(6 "In2.Cu" signal)
		(8 "In3.Cu" signal)
		(10 "In4.Cu" jumper)
		(12 "In5.Cu" signal)
		(14 "In6.Cu" signal)
		(16 "In7.Cu" signal)
		(18 "In8.Cu" signal)
		(2 "B.Cu" signal)
		(9 "F.Adhes" user "F.Adhesive")
		(11 "B.Adhes" user "B.Adhesive")
		(13 "F.Paste" user)
		(15 "B.Paste" user)
		(5 "F.SilkS" user "F.Silkscreen")
		(7 "B.SilkS" user "B.Silkscreen")
		(1 "F.Mask" user)
		(3 "B.Mask" user)
		(17 "Dwgs.User" user "User.Drawings")
		(19 "Cmts.User" user "User.Comments")
		(21 "Eco1.User" user "User.Eco1")
		(23 "Eco2.User" user "User.Eco2")
		(25 "Edge.Cuts" user)
		(27 "Margin" user)
		(31 "F.CrtYd" user "F.Courtyard")
		(29 "B.CrtYd" user "B.Courtyard")
		(35 "F.Fab" user)
		(33 "B.Fab" user)
	)
	(footprint "antmicro-footprints:C_0402_1005Metric"
		(layer "F.Cu")
		(at 94 63.5 180)
		(descr "Capacitor SMD 0402")
		(tags "capacitor SMD 0402")
		(property "Reference" "C40"
			(at -9.05 -0.6 0)
			(layer "F.SilkS")
			(effects
				(font
					(size 0.7 0.7)
					(thickness 0.15)
				)
				(justify right top)
			)
		)
		(property "Value" "C_100n_0402"
			(at -1.022927 2.155213 0)
			(layer "F.Fab")
			(effects
				(font
					(size 0.7 0.7)
					(thickness 0.15)
				)
				(justify right top)
			)
		)
		(property "Datasheet" "https://www.murata.com/products/productdetail?partno=GRM155R61H104KE14%23"
			(at 0 0 0)
			(layer "F.Fab")
			(hide yes)
			(effects
				(font
					(size 1.27 1.27)
					(thickness 0.15)
				)
			)
		)
		(property "Description" "SMD Multilayer Ceramic Capacitor, 0.1 µF, 50 V, 0402 [1005 Metric], ± 10%, X5R, GRM Series"
			(at 0 0 0)
			(layer "F.Fab")
			(hide yes)
			(effects
				(font
					(size 1.27 1.27)
					(thickness 0.15)
				)
			)
		)
		(property "MPN" "GRM155R61H104KE14D"
			(at 0 0 180)
			(unlocked yes)
			(layer "F.Fab")
			(hide yes)
			(effects
				(font
					(size 1 1)
					(thickness 0.15)
				)
			)
		)
		(property "Manufacturer" "Murata"
			(at 0 0 180)
			(unlocked yes)
			(layer "F.Fab")
			(hide yes)
			(effects
				(font
					(size 1 1)
					(thickness 0.15)
				)
			)
		)
		(property "License" "Apache-2.0"
			(at 0 0 180)
			(unlocked yes)
			(layer "F.Fab")
			(hide yes)
			(effects
				(font
					(size 1 1)
					(thickness 0.15)
				)
			)
		)
		(property "Author" "Antmicro"
			(at 0 0 180)
			(unlocked yes)
			(layer "F.Fab")
			(hide yes)
			(effects
				(font
					(size 1 1)
					(thickness 0.15)
				)
			)
		)
		(property "Val" "100n"
			(at 0 0 180)
			(unlocked yes)
			(layer "F.Fab")
			(hide yes)
			(effects
				(font
					(size 1 1)
					(thickness 0.15)
				)
			)
		)
		(property "Voltage" "50V"
			(at 0 0 180)
			(unlocked yes)
			(layer "F.Fab")
			(hide yes)
			(effects
				(font
					(size 1 1)
					(thickness 0.15)
				)
			)
		)
		(property "Dielectric" "X5R"
			(at 0 0 180)
			(unlocked yes)
			(layer "F.Fab")
			(hide yes)
			(effects
				(font
					(size 1 1)
					(thickness 0.15)
				)
			)
		)
		(sheetname "/SoM_Power/")
		(sheetfile "som_power.kicad_sch")
		(attr smd)
		(fp_poly
			(pts
				(xy -0.925 -0.47) (xy 0.925 -0.47) (xy 0.925 0.47) (xy -0.925 0.47)
			)
			(stroke
				(width 0.05)
				(type default)
			)
			(fill no)
			(layer "F.CrtYd")
		)
		(fp_line
			(start 0.504 0.248)
			(end -0.494 0.248)
			(stroke
				(width 0.15)
				(type solid)
			)
			(layer "F.Fab")
		)
		(fp_line
			(start 0.504 -0.25)
			(end 0.504 0.248)
			(stroke
				(width 0.15)
				(type solid)
			)
			(layer "F.Fab")
		)
		(fp_line
			(start -0.494 0.248)
			(end -0.494 -0.25)
			(stroke
				(width 0.15)
				(type solid)
			)
			(layer "F.Fab")
		)
		(fp_line
			(start -0.494 -0.25)
			(end 0.504 -0.25)
			(stroke
				(width 0.15)
				(type solid)
			)
			(layer "F.Fab")
		)
		(fp_text user "Author: Antmicro"
			(at -0.939 3.399 0)
			(layer "F.Fab")
			(effects
				(font
					(size 0.7 0.7)
					(thickness 0.15)
				)
				(justify right top)
			)
		)
		(fp_text user "License: Apache-2.0"
			(at -0.939 5.799 0)
			(layer "F.Fab")
			(effects
				(font
					(size 0.7 0.7)
					(thickness 0.15)
				)
				(justify right top)
			)
		)
		(fp_text user "${REFERENCE}"
			(at -0.939 4.599 0)
			(layer "F.Fab")
			(effects
				(font
					(size 0.7 0.7)
					(thickness 0.15)
				)
				(justify right top)
			)
		)
		(pad "1" smd roundrect
			(at -0.48 0 180)
			(size 0.59 0.64)
			(layers "F.Cu" "F.Mask" "F.Paste")
			(roundrect_rratio 0.25)
			(net 1 "GND")
			(pintype "passive")
		)
		(pad "2" smd roundrect
			(at 0.48 0 180)
			(size 0.59 0.64)
			(layers "F.Cu" "F.Mask" "F.Paste")
			(roundrect_rratio 0.25)
			(net 4 "+3V3_AON")
			(pintype "passive")
		)
	)
	(footprint "antmicro-footprints:C_0603_1608Metric_EIA"
		(layer "F.Cu")
		(at 173.55 113.59 -90)
		(descr "Capacitor SMD 0603, IPC-7351 Density Level A")
		(tags "Capacitor 0603")
		(property "Reference" "C63"
			(at -1.21 6.839468 90)
			(layer "F.SilkS")
			(effects
				(font
					(size 0.7 0.7)
					(thickness 0.15)
				)
				(justify right top)
			)
		)
		(property "Value" "C_22u_16V_0603"
			(at -1.42757 1.770288 90)
			(layer "F.Fab")
			(effects
				(font
					(size 0.7 0.7)
					(thickness 0.15)
				)
				(justify right top)
			)
		)
		(property "Datasheet" "https://product.samsungsem.com/mlcc/CL10A226MO7JZN.do"
			(at 0 0 90)
			(layer "F.Fab")
			(hide yes)
			(effects
				(font
					(size 1.27 1.27)
					(thickness 0.15)
				)
			)
		)
		(property "Description" "SMD Multilayer Ceramic Capacitor"
			(at 0 0 90)
			(layer "F.Fab")
			(hide yes)
			(effects
				(font
					(size 1.27 1.27)
					(thickness 0.15)
				)
			)
		)
		(property "Manufacturer" "Samsung Electro-Mechanics"
			(at 0 0 270)
			(unlocked yes)
			(layer "F.Fab")
			(hide yes)
			(effects
				(font
					(size 1 1)
					(thickness 0.15)
				)
			)
		)
		(property "MPN" "CL10A226MO7JZNC"
			(at 0 0 270)
			(unlocked yes)
			(layer "F.Fab")
			(hide yes)
			(effects
				(font
					(size 1 1)
					(thickness 0.15)
				)
			)
		)
		(property "Val" "22u"
			(at 0 0 270)
			(unlocked yes)
			(layer "F.Fab")
			(hide yes)
			(effects
				(font
					(size 1 1)
					(thickness 0.15)
				)
			)
		)
		(property "License" "Apache-2.0"
			(at 0 0 270)
			(unlocked yes)
			(layer "F.Fab")
			(hide yes)
			(effects
				(font
					(size 1 1)
					(thickness 0.15)
				)
			)
		)
		(property "Author" "Antmicro"
			(at 0 0 270)
			(unlocked yes)
			(layer "F.Fab")
			(hide yes)
			(effects
				(font
					(size 1 1)
					(thickness 0.15)
				)
			)
		)
		(property "Voltage" "16V"
			(at 0 0 270)
			(unlocked yes)
			(layer "F.Fab")
			(hide yes)
			(effects
				(font
					(size 1 1)
					(thickness 0.15)
				)
			)
		)
		(property "Dielectric" ""
			(at 0 0 270)
			(unlocked yes)
			(layer "F.Fab")
			(hide yes)
			(effects
				(font
					(size 1 1)
					(thickness 0.15)
				)
			)
		)
		(sheetname "/DCDC/")
		(sheetfile "dcdc.kicad_sch")
		(attr smd)
		(fp_line
			(start -0.15 0.55)
			(end 0.15 0.55)
			(stroke
				(width 0.15)
				(type solid)
			)
			(layer "F.SilkS")
		)
		(fp_line
			(start -0.15 -0.55)
			(end 0.15 -0.55)
			(stroke
				(width 0.15)
				(type solid)
			)
			(layer "F.SilkS")
		)
		(fp_rect
			(start -1.25 -0.65)
			(end 1.25 0.65)
			(stroke
				(width 0.05)
				(type solid)
			)
			(fill no)
			(layer "F.CrtYd")
		)
		(fp_rect
			(start -0.8 -0.45)
			(end 0.8 0.45)
			(stroke
				(width 0.15)
				(type solid)
			)
			(fill no)
			(layer "F.Fab")
		)
		(fp_text user "License: Apache-2.0"
			(at -1.682 5.895 90)
			(layer "F.Fab")
			(effects
				(font
					(size 0.7 0.7)
					(thickness 0.15)
				)
				(justify right top)
			)
		)
		(fp_text user "Author: Antmicro"
			(at -1.682 4.894 90)
			(layer "F.Fab")
			(effects
				(font
					(size 0.7 0.7)
					(thickness 0.15)
				)
				(justify right top)
			)
		)
		(fp_text user "${REFERENCE}"
			(at -1.682 3.895 90)
			(layer "F.Fab")
			(effects
				(font
					(size 0.7 0.7)
					(thickness 0.15)
				)
				(justify right top)
			)
		)
		(pad "1" smd roundrect
			(at -0.7 0 270)
			(size 0.8 1.1)
			(layers "F.Cu" "F.Mask" "F.Paste")
			(roundrect_rratio 0.2)
			(net 1 "GND")
			(pintype "passive")
		)
		(pad "2" smd roundrect
			(at 0.7 0 270)
			(size 0.8 1.1)
			(layers "F.Cu" "F.Mask" "F.Paste")
			(roundrect_rratio 0.2)
			(net 253 "/DCDC/5V_OUT")
			(pintype "passive")
		)
	)
	(footprint "antmicro-footprints:R_0402_1005Metric"
		(layer "F.Cu")
		(at 90 65.45)
		(descr "Resistor SMD 0402")
		(tags "resistor SMD 0402")
		(property "Reference" "R297"
			(at -1.1 1.3 0)
			(layer "F.SilkS")
			(effects
				(font
					(size 0.7 0.7)
					(thickness 0.15)
				)
				(justify left bottom)
			)
		)
		(property "Value" "R_0R_0402"
			(at -1.011843 1.772046 0)
			(layer "F.Fab")
			(effects
				(font
					(size 0.7 0.7)
					(thickness 0.15)
				)
				(justify left bottom)
			)
		)
		(property "Datasheet" "https://industrial.panasonic.com/cdbs/www-data/pdf/RDA0000/AOA0000C301.pdf"
			(at 0 0 0)
			(layer "F.Fab")
			(hide yes)
			(effects
				(font
					(size 1.27 1.27)
					(thickness 0.15)
				)
			)
		)
		(property "Description" "SMD Chip Resistor, Jumper, 0 ohm, 100 mW, 0402 [1005 Metric], Thick Film, General Purpose"
			(at 0 0 0)
			(layer "F.Fab")
			(hide yes)
			(effects
				(font
					(size 1.27 1.27)
					(thickness 0.15)
				)
			)
		)
		(property "MPN" "ERJ2GE0R00X"
			(at 0 0 0)
			(unlocked yes)
			(layer "F.Fab")
			(hide yes)
			(effects
				(font
					(size 1 1)
					(thickness 0.15)
				)
			)
		)
		(property "Manufacturer" "Panasonic"
			(at 0 0 0)
			(unlocked yes)
			(layer "F.Fab")
			(hide yes)
			(effects
				(font
					(size 1 1)
					(thickness 0.15)
				)
			)
		)
		(property "License" "Apache-2.0"
			(at 0 0 0)
			(unlocked yes)
			(layer "F.Fab")
			(hide yes)
			(effects
				(font
					(size 1 1)
					(thickness 0.15)
				)
			)
		)
		(property "Author" "Antmicro"
			(at 0 0 0)
			(unlocked yes)
			(layer "F.Fab")
			(hide yes)
			(effects
				(font
					(size 1 1)
					(thickness 0.15)
				)
			)
		)
		(property "Val" "0R"
			(at 0 0 0)
			(unlocked yes)
			(layer "F.Fab")
			(hide yes)
			(effects
				(font
					(size 1 1)
					(thickness 0.15)
				)
			)
		)
		(property "Tolerance" "~"
			(at 0 0 0)
			(unlocked yes)
			(layer "F.Fab")
			(hide yes)
			(effects
				(font
					(size 1 1)
					(thickness 0.15)
				)
			)
		)
		(property "Current" "1A"
			(at 0 0 0)
			(unlocked yes)
			(layer "F.Fab")
			(hide yes)
			(effects
				(font
					(size 1 1)
					(thickness 0.15)
				)
			)
		)
		(sheetname "/SoM_Power/")
		(sheetfile "som_power.kicad_sch")
		(attr smd)
		(fp_poly
			(pts
				(xy -0.925 -0.47) (xy -0.925 0.47) (xy 0.925 0.47) (xy 0.925 -0.47)
			)
			(stroke
				(width 0.05)
				(type default)
			)
			(fill no)
			(layer "F.CrtYd")
		)
		(fp_poly
			(pts
				(xy -0.5 -0.25) (xy -0.5 0.25) (xy 0.5 0.25) (xy 0.5 -0.25)
			)
			(stroke
				(width 0.15)
				(type solid)
			)
			(fill no)
			(layer "F.Fab")
		)
		(fp_text user "${REFERENCE}"
			(at -0.95 3.168 0)
			(layer "F.Fab")
			(effects
				(font
					(size 0.7 0.7)
					(thickness 0.15)
				)
				(justify left bottom)
			)
		)
		(fp_text user "License: Apache-2.0"
			(at -0.949999 5.169 0)
			(layer "F.Fab")
			(effects
				(font
					(size 0.7 0.7)
					(thickness 0.15)
				)
				(justify left bottom)
			)
		)
		(fp_text user "Author: Antmicro"
			(at -0.95 4.169 0)
			(layer "F.Fab")
			(effects
				(font
					(size 0.7 0.7)
					(thickness 0.15)
				)
				(justify left bottom)
			)
		)
		(pad "1" smd roundrect
			(at -0.48 0)
			(size 0.59 0.64)
			(layers "F.Cu" "F.Mask" "F.Paste")
			(roundrect_rratio 0.25)
			(net 887 "Net-(Q17-D)")
			(pintype "passive")
		)
		(pad "2" smd roundrect
			(at 0.48 0)
			(size 0.59 0.64)
			(layers "F.Cu" "F.Mask" "F.Paste")
			(roundrect_rratio 0.25)
			(net 1032 "/SoM_Power/~{FORCE_SHDN}")
			(pintype "passive")
		)
	)
	(footprint "antmicro-footprints:R_0402_1005Metric"
		(layer "F.Cu")
		(at 195.1 126.3)
		(descr "Resistor SMD 0402")
		(tags "resistor SMD 0402")
		(property "Reference" "R83"
			(at 0.15 -1.35 0)
			(layer "F.SilkS")
			(effects
				(font
					(size 0.7 0.7)
					(thickness 0.15)
				)
				(justify left bottom)
			)
		)
		(property "Value" "R_10k_0402"
			(at -1.011843 1.772047 0)
			(layer "F.Fab")
			(effects
				(font
					(size 0.7 0.7)
					(thickness 0.15)
				)
				(justify left bottom)
			)
		)
		(property "Datasheet" "https://www.bourns.com/docs/product-datasheets/cr.pdf"
			(at 0 0 0)
			(layer "F.Fab")
			(hide yes)
			(effects
				(font
					(size 1.27 1.27)
					(thickness 0.15)
				)
			)
		)
		(property "Description" "SMD Chip Resistor, 10 kohm, ± 1%, 62.5 mW, 0402 [1005 Metric], Thick Film, General Purpose"
			(at 0 0 0)
			(layer "F.Fab")
			(hide yes)
			(effects
				(font
					(size 1.27 1.27)
					(thickness 0.15)
				)
			)
		)
		(property "MPN" "CR0402-FX-1002GLF"
			(at 0 0 0)
			(unlocked yes)
			(layer "F.Fab")
			(hide yes)
			(effects
				(font
					(size 1 1)
					(thickness 0.15)
				)
			)
		)
		(property "Manufacturer" "Bourns"
			(at 0 0 0)
			(unlocked yes)
			(layer "F.Fab")
			(hide yes)
			(effects
				(font
					(size 1 1)
					(thickness 0.15)
				)
			)
		)
		(property "License" "Apache-2.0"
			(at 0 0 0)
			(unlocked yes)
			(layer "F.Fab")
			(hide yes)
			(effects
				(font
					(size 1 1)
					(thickness 0.15)
				)
			)
		)
		(property "Author" "Antmicro"
			(at 0 0 0)
			(unlocked yes)
			(layer "F.Fab")
			(hide yes)
			(effects
				(font
					(size 1 1)
					(thickness 0.15)
				)
			)
		)
		(property "Val" "10k"
			(at 0 0 0)
			(unlocked yes)
			(layer "F.Fab")
			(hide yes)
			(effects
				(font
					(size 1 1)
					(thickness 0.15)
				)
			)
		)
		(property "Tolerance" "1%"
			(at 0 0 0)
			(unlocked yes)
			(layer "F.Fab")
			(hide yes)
			(effects
				(font
					(size 1 1)
					(thickness 0.15)
				)
			)
		)
		(sheetname "/USB Hub/")
		(sheetfile "usb_hub.kicad_sch")
		(attr smd)
		(fp_rect
			(start -0.925 -0.47)
			(end 0.925 0.47)
			(stroke
				(width 0.05)
				(type default)
			)
			(fill no)
			(layer "F.CrtYd")
		)
		(fp_rect
			(start -0.5 -0.25)
			(end 0.5 0.25)
			(stroke
				(width 0.15)
				(type solid)
			)
			(fill no)
			(layer "F.Fab")
		)
		(fp_text user "Author: Antmicro"
			(at -0.95 4.169 0)
			(layer "F.Fab")
			(effects
				(font
					(size 0.7 0.7)
					(thickness 0.15)
				)
				(justify left bottom)
			)
		)
		(fp_text user "${REFERENCE}"
			(at -0.95 3.168 0)
			(layer "F.Fab")
			(effects
				(font
					(size 0.7 0.7)
					(thickness 0.15)
				)
				(justify left bottom)
			)
		)
		(fp_text user "License: Apache-2.0"
			(at -0.95 5.169 0)
			(layer "F.Fab")
			(effects
				(font
					(size 0.7 0.7)
					(thickness 0.15)
				)
				(justify left bottom)
			)
		)
		(pad "1" smd roundrect
			(at -0.48 0)
			(size 0.59 0.64)
			(layers "F.Cu" "F.Mask" "F.Paste")
			(roundrect_rratio 0.25)
			(net 2 "+3V3")
			(pintype "passive")
		)
		(pad "2" smd roundrect
			(at 0.48 0)
			(size 0.59 0.64)
			(layers "F.Cu" "F.Mask" "F.Paste")
			(roundrect_rratio 0.25)
			(net 917 "/USB Hub/TEST2")
			(pintype "passive")
		)
	)
)
